(kicad_pcb
	(version 20221018)
	(generator pcbnew)
	(general
    (thickness 0.908)
  )
	(paper "A4")
	(title_block
    (title "HDMI-MIPI Bridge")
    (date "2024-04-24")
    (rev "1.3.2")
		(comment 9 "footprints 86-89 of 121")
	)
	(layers
    (0 "F.Cu" signal)
    (1 "In1.Cu" signal)
    (2 "In2.Cu" signal)
    (31 "B.Cu" signal)
    (32 "B.Adhes" user "B.Adhesive")
    (33 "F.Adhes" user "F.Adhesive")
    (34 "B.Paste" user)
    (35 "F.Paste" user)
    (36 "B.SilkS" user "B.Silkscreen")
    (37 "F.SilkS" user "F.Silkscreen")
    (38 "B.Mask" user)
    (39 "F.Mask" user)
    (40 "Dwgs.User" user "User.Drawings")
    (41 "Cmts.User" user "User.Comments")
    (42 "Eco1.User" user "User.Eco1")
    (43 "Eco2.User" user "User.Eco2")
    (44 "Edge.Cuts" user)
    (45 "Margin" user)
    (46 "B.CrtYd" user "B.Courtyard")
    (47 "F.CrtYd" user "F.Courtyard")
    (48 "B.Fab" user)
    (49 "F.Fab" user)
  )
	(footprint "antmicro-footprints:FB_0805_2012Metric" (layer "F.Cu")
    (at 153.4 105.45 180)
    (descr "FERRITE BEAD 0805")
    (tags "FERRITE BEAD 0805")
    (property "Author" "Antmicro")
    (property "Current" "")
    (property "License" "Apache-2.0")
    (property "MPN" "742792096")
    (property "Manufacturer" "Würth Elektronik")
    (property "Public" "False")
    (property "Sheetfile" "channel2.kicad_sch")
    (property "Sheetname" "Channel 2")
    (property "Val" "1kZ/0.8A")
    (property "ki_description" "Ferrite Beads WE-CBF 0805 100MHz 1kOhm 1A, High Current")
    (property "ki_keywords" "FERRITE BEAD, PASSIVE")
    (attr smd)
    (fp_text reference "FB11" (at 1.24 1.12 180) (layer "F.SilkS")
        (effects (font (size 0.65 0.65) (thickness 0.13)) (justify left bottom))
    )
    (fp_text value "FB_1kZ_0.8A_WE-CBF_0805" (at 0 1.8 180) (layer "F.Fab")
        (effects (font (size 0.65 0.65) (thickness 0.13)) (justify left bottom))
    )
    (fp_text user "Author: Antmicro" (at -1.9 4.4 180) (layer "F.Fab") hide
        (effects (font (size 0.7 0.7) (thickness 0.15)) (justify left bottom))
    )
    (fp_text user "License: Apache-2.0" (at -1.9 5.75 180) (layer "F.Fab") hide
        (effects (font (size 0.7 0.7) (thickness 0.15)) (justify left bottom))
    )
    (fp_text user "${REFERENCE}" (at -1.9 3.1 180) (layer "F.Fab") hide
        (effects (font (size 0.7 0.7) (thickness 0.15)) (justify left bottom))
    )
    (fp_line (start -0.319 0.698) (end 0.281 0.698)
      (stroke (width 0.15) (type solid)) (layer "F.SilkS"))
    (fp_line (start -0.299 -0.698) (end 0.299 -0.698)
      (stroke (width 0.15) (type solid)) (layer "F.SilkS"))
    (fp_rect (start 1.95 -0.9) (end -1.95 0.9)
      (stroke (width 0.05) (type default)) (fill none) (layer "F.CrtYd"))
    (fp_line (start -0.948 -0.681) (end 0.948 -0.681)
      (stroke (width 0.15) (type solid)) (layer "F.Fab"))
    (fp_line (start -0.948 -0.676) (end -0.948 0.676)
      (stroke (width 0.15) (type solid)) (layer "F.Fab"))
    (fp_line (start -0.948 0.681) (end 0.948 0.681)
      (stroke (width 0.15) (type solid)) (layer "F.Fab"))
    (fp_line (start 0.948 -0.676) (end 0.948 0.676)
      (stroke (width 0.15) (type solid)) (layer "F.Fab"))
    (pad "1" smd roundrect (at -1.1 0 180) (size 1.2 1.3) (layers "F.Cu" "F.Paste" "F.Mask") (roundrect_rratio 0.25)
      (net 33 "Net-(U4B-VDDC1)") (pintype "passive"))
    (pad "2" smd roundrect (at 1.1 0 180) (size 1.2 1.3) (layers "F.Cu" "F.Paste" "F.Mask") (roundrect_rratio 0.25)
      (net 25 "CH2_1V2") (pintype "passive"))
  )
	(footprint "antmicro-footprints:C_0402_1005Metric" (layer "F.Cu")
    (at 131 109.4)
    (descr "Capacitor SMD 0402")
    (tags "capacitor SMD 0402")
    (property "Author" "Antmicro")
    (property "Dielectric" "X5R")
    (property "License" "Apache-2.0")
    (property "MPN" "GRM155R61H104KE14D")
    (property "Manufacturer" "Murata")
    (property "Public" "False")
    (property "Sheetfile" "channel1.kicad_sch")
    (property "Sheetname" "Channel 1")
    (property "Val" "100n")
    (property "Voltage" "50V")
    (property "ki_description" "SMD Multilayer Ceramic Capacitor, 0.1 µF, 50 V, 0402 [1005 Metric], ± 10%, X5R, GRM Series")
    (property "ki_keywords" "0402, SMT, CAPACITOR, PASSIVE, CERAMIC, MLCC")
    (attr smd)
    (fp_text reference "C30" (at -1.6 7.6) (layer "F.SilkS")
        (effects (font (size 0.65 0.65) (thickness 0.13)) (justify left bottom))
    )
    (fp_text value "C_100n_0402" (at 0 1.4) (layer "F.Fab")
        (effects (font (size 0.65 0.65) (thickness 0.13)) (justify left bottom))
    )
    (fp_text user "Author: Antmicro" (at -0.932 4.17) (layer "F.Fab") hide
        (effects (font (size 0.7 0.7) (thickness 0.15)) (justify left bottom))
    )
    (fp_text user "License: Apache-2.0" (at -0.932 5.17) (layer "F.Fab") hide
        (effects (font (size 0.7 0.7) (thickness 0.15)) (justify left bottom))
    )
    (fp_text user "${REFERENCE}" (at -0.932 3.168) (layer "F.Fab") hide
        (effects (font (size 0.7 0.7) (thickness 0.15)) (justify left bottom))
    )
    (fp_rect (start -0.925 -0.47) (end 0.925 0.47)
      (stroke (width 0.05) (type default)) (fill none) (layer "F.CrtYd"))
    (fp_line (start -0.494 -0.25) (end 0.504 -0.25)
      (stroke (width 0.15) (type solid)) (layer "F.Fab"))
    (fp_line (start -0.494 0.248) (end -0.494 -0.25)
      (stroke (width 0.15) (type solid)) (layer "F.Fab"))
    (fp_line (start 0.504 -0.25) (end 0.504 0.248)
      (stroke (width 0.15) (type solid)) (layer "F.Fab"))
    (fp_line (start 0.504 0.248) (end -0.494 0.248)
      (stroke (width 0.15) (type solid)) (layer "F.Fab"))
    (pad "1" smd roundrect (at -0.48 0) (size 0.59 0.64) (layers "F.Cu" "F.Paste" "F.Mask") (roundrect_rratio 0.25)
      (net 2 "GND") (pintype "passive"))
    (pad "2" smd roundrect (at 0.48 0) (size 0.59 0.64) (layers "F.Cu" "F.Paste" "F.Mask") (roundrect_rratio 0.25)
      (net 100 "/Channel 1/CH1_AVDD33") (pintype "passive"))
  )
	(footprint "antmicro-footprints:C_0402_1005Metric" (layer "F.Cu")
    (at 148 105.45 -90)
    (descr "Capacitor SMD 0402")
    (tags "capacitor SMD 0402")
    (property "Author" "Antmicro")
    (property "Dielectric" "C0G")
    (property "License" "Apache-2.0")
    (property "MPN" "C0402C470J5GACTU")
    (property "Manufacturer" "KEMET")
    (property "Public" "False")
    (property "Sheetfile" "channel2.kicad_sch")
    (property "Sheetname" "Channel 2")
    (property "Val" "47p")
    (property "Voltage" "")
    (property "ki_description" "SMD Multilayer Ceramic Capacitor, 47 pF, 50 V, 0402 [1005 Metric], ± 5%, C0G / NP0, C Series KEMET")
    (property "ki_keywords" "0402, SMT, CAPACITOR, PASSIVE, CERAMIC, MLCC")
    (attr smd)
    (fp_text reference "C36" (at -1.15 -2.4 90) (layer "F.SilkS")
        (effects (font (size 0.65 0.65) (thickness 0.13)) (justify right bottom))
    )
    (fp_text value "C_47p_0402" (at 0 1.4 90) (layer "F.Fab")
        (effects (font (size 0.65 0.65) (thickness 0.13)) (justify right bottom))
    )
    (fp_text user "${REFERENCE}" (at -0.932 3.168 90) (layer "F.Fab") hide
        (effects (font (size 0.7 0.7) (thickness 0.15)) (justify right bottom))
    )
    (fp_text user "License: Apache-2.0" (at -0.932 5.17 90) (layer "F.Fab") hide
        (effects (font (size 0.7 0.7) (thickness 0.15)) (justify right bottom))
    )
    (fp_text user "Author: Antmicro" (at -0.932 4.17 90) (layer "F.Fab") hide
        (effects (font (size 0.7 0.7) (thickness 0.15)) (justify right bottom))
    )
    (fp_rect (start -0.925 -0.47) (end 0.925 0.47)
      (stroke (width 0.05) (type default)) (fill none) (layer "F.CrtYd"))
    (fp_line (start -0.494 -0.25) (end 0.504 -0.25)
      (stroke (width 0.15) (type solid)) (layer "F.Fab"))
    (fp_line (start -0.494 0.248) (end -0.494 -0.25)
      (stroke (width 0.15) (type solid)) (layer "F.Fab"))
    (fp_line (start 0.504 -0.25) (end 0.504 0.248)
      (stroke (width 0.15) (type solid)) (layer "F.Fab"))
    (fp_line (start 0.504 0.248) (end -0.494 0.248)
      (stroke (width 0.15) (type solid)) (layer "F.Fab"))
    (pad "1" smd roundrect (at -0.48 0 270) (size 0.59 0.64) (layers "F.Cu" "F.Paste" "F.Mask") (roundrect_rratio 0.25)
      (net 2 "GND") (pintype "passive"))
    (pad "2" smd roundrect (at 0.48 0 270) (size 0.59 0.64) (layers "F.Cu" "F.Paste" "F.Mask") (roundrect_rratio 0.25)
      (net 9 "+3V3") (pintype "passive"))
  )
	(footprint "antmicro-footprints:R_0402_1005Metric" (layer "F.Cu")
    (at 163.39 102.27 -90)
    (descr "Resistor SMD 0402")
    (tags "resistor SMD 0402")
    (property "Author" "Antmicro")
    (property "License" "Apache-2.0")
    (property "MPN" "CR0402-FX-1002GLF")
    (property "Manufacturer" "Bourns")
    (property "Public" "False")
    (property "Sheetfile" "channel2.kicad_sch")
    (property "Sheetname" "Channel 2")
    (property "Tolerance" "1%")
    (property "Val" "10k")
    (property "ki_description" "SMD Chip Resistor, 10 kohm, ± 1%, 62.5 mW, 0402 [1005 Metric], Thick Film, General Purpose")
    (property "ki_keywords" "0402, SMT, RESISTOR, PASSIVE")
    (attr smd)
    (fp_text reference "R24" (at -3.25 11.68 90) (layer "F.SilkS")
        (effects (font (size 0.65 0.65) (thickness 0.13)) (justify left bottom))
    )
    (fp_text value "R_10k_0402" (at 0 1.4 -90) (layer "F.Fab")
        (effects (font (size 0.65 0.65) (thickness 0.13)) (justify left bottom))
    )
    (fp_text user "Author: Antmicro" (at -0.95 4.169 -90) (layer "F.Fab") hide
        (effects (font (size 0.7 0.7) (thickness 0.15)) (justify left bottom))
    )
    (fp_text user "${REFERENCE}" (at -0.95 3.168 -90) (layer "F.Fab") hide
        (effects (font (size 0.7 0.7) (thickness 0.15)) (justify left bottom))
    )
    (fp_text user "License: Apache-2.0" (at -0.95 5.169 -90) (layer "F.Fab") hide
        (effects (font (size 0.7 0.7) (thickness 0.15)) (justify left bottom))
    )
    (fp_rect (start -0.925 -0.47) (end 0.925 0.47)
      (stroke (width 0.05) (type default)) (fill none) (layer "F.CrtYd"))
    (fp_rect (start -0.5 -0.25) (end 0.5 0.25)
      (stroke (width 0.15) (type solid)) (fill none) (layer "F.Fab"))
    (pad "1" smd roundrect (at -0.48 0 270) (size 0.59 0.64) (layers "F.Cu" "F.Paste" "F.Mask") (roundrect_rratio 0.25)
      (net 139 "/Channel 2/HDMI2_DDC_SCL") (pintype "passive"))
    (pad "2" smd roundrect (at 0.48 0 270) (size 0.59 0.64) (layers "F.Cu" "F.Paste" "F.Mask") (roundrect_rratio 0.25)
      (net 14 "+5V") (pintype "passive"))
  )
)
